# BASEBOARD_FAB2 (Tioga Pass) — schematic netlist excerpt (pin names and nets, part order shuffled) for the footprints in the layout excerpt that follows; sources: Cadence DE-HDL packaged netlist, KiCad conversion of Wiwynn_Tioga_Pass_MB.brd

C4L1  CAP  10UF 4V 20% X6S  pkg 0603LF  page 232 : A = PVPP_DEF ; B = GND
R3M8  RES  100.0K 1% CHIP  pkg 0402  page 116 : A = P2E_SSB_BMC_RX_C_DP ; B = GND
C2R14  CAP  0.22UF 16V 10% X7R  pkg 0402  page 106 : A = P3E_CPU0_PE3_OCP_TXP<5> ; B = P3E_OCP_CPU0_PE3_C_TXP<5>

(kicad_pcb
	(version 20260206)
	(generator "pcbnew")
	(generator_version "10.0")
	(general
		(thickness 1.6)
		(legacy_teardrops no)
	)
	(paper "A4")
	(title_block
		(title "Wiwynn_Tioga_Pass_MB.brd")
		(comment 1 "Tioga Pass / footprints 4504-4506 of 4770")
	)
	(layers
		(0 "F.Cu" signal "TOP")
		(4 "In1.Cu" signal "L2GND")
		(6 "In2.Cu" signal "L3")
		(8 "In3.Cu" signal "L4GND")
		(10 "In4.Cu" signal "L5")
		(12 "In5.Cu" signal "L6GND")
		(14 "In6.Cu" signal "L7VCC")
		(16 "In7.Cu" signal "L8VCC")
		(18 "In8.Cu" signal "L9GND")
		(20 "In9.Cu" signal "L10")
		(22 "In10.Cu" signal "L11GND")
		(24 "In11.Cu" signal "L12")
		(26 "In12.Cu" signal "L13GND")
		(2 "B.Cu" signal "BOTTOM")
		(9 "F.Adhes" user "F.Adhesive")
		(11 "B.Adhes" user "B.Adhesive")
		(13 "F.Paste" user "Package Geometry/Pastemask Top")
		(15 "B.Paste" user "Package Geometry/Pastemask Bottom")
		(5 "F.SilkS" user "Ref Des/Silkscreen Top")
		(7 "B.SilkS" user "Ref Des/Silkscreen Bottom")
		(1 "F.Mask" user "Board Geometry/Soldermask Top")
		(3 "B.Mask" user "Board Geometry/Soldermask Bottom")
		(17 "Dwgs.User" user "User.Drawings")
		(19 "Cmts.User" user "User.Comments")
		(21 "Eco1.User" user "User.Eco1")
		(23 "Eco2.User" user "User.Eco2")
		(25 "Edge.Cuts" user "Board Geometry/Outline")
		(27 "Margin" user)
		(31 "F.CrtYd" user "Package Geometry/Place Bound Top")
		(29 "B.CrtYd" user "Package Geometry/Place Bound Bottom")
		(35 "F.Fab" user "Ref Des/Assembly Top")
		(33 "B.Fab" user "Ref Des/Assembly Bottom")
	)
	(footprint ""
		(layer "B.Cu")
		(at 388.366 -129.99974 180)
		(property "Reference" "R3M8"
			(at 0 0 0)
			(layer "B.SilkS")
			(hide yes)
			(effects
				(font
					(size 1.27 1.27)
				)
				(justify mirror)
			)
		)
		(property "Value" ""
			(at 0 0 0)
			(layer "B.Fab")
			(effects
				(font
					(size 1.27 1.27)
				)
				(justify mirror)
			)
		)
		(duplicate_pad_numbers_are_jumpers no)
		(fp_poly
			(pts
				(xy 0.2794 -0.1016) (xy -0.2794 -0.1016) (xy -0.2794 0.9906) (xy 0.2794 0.9906)
			)
			(stroke
				(width 0)
				(type default)
			)
			(fill no)
			(layer "B.CrtYd")
		)
		(fp_line
			(start 0.2794 0.9906)
			(end -0.2794 0.9906)
			(stroke
				(width 0.1)
				(type default)
			)
			(layer "B.Fab")
		)
		(fp_line
			(start 0.2794 -0.1016)
			(end 0.2794 0.9906)
			(stroke
				(width 0.1)
				(type default)
			)
			(layer "B.Fab")
		)
		(fp_line
			(start -0.2794 0.9906)
			(end -0.2794 -0.1016)
			(stroke
				(width 0.1)
				(type default)
			)
			(layer "B.Fab")
		)
		(fp_line
			(start -0.2794 -0.1016)
			(end 0.2794 -0.1016)
			(stroke
				(width 0.1)
				(type default)
			)
			(layer "B.Fab")
		)
		(pad "1" smd rect
			(at 0 0)
			(size 0.508 0.508)
			(layers "B.Cu" "B.Mask" "B.Paste")
			(net "P2E_SSB_BMC_RX_C_DP")
		)
		(pad "2" smd rect
			(at 0 0.889)
			(size 0.508 0.508)
			(layers "B.Cu" "B.Mask" "B.Paste")
			(net "GND")
		)
		(zone
			(layer "B.Cu")
			(hatch none 0.5)
			(connect_pads
				(clearance 0)
			)
			(min_thickness 0.25)
			(keepout
				(tracks not_allowed)
				(vias allowed)
				(pads allowed)
				(copperpour not_allowed)
				(footprints allowed)
			)
			(placement
				(enabled no)
				(sheetname "")
			)
			(fill
				(thermal_gap 0.5)
				(thermal_bridge_width 0.5)
				(island_removal_mode 0)
			)
			(polygon
				(pts
					(xy 388.112 -130.63474) (xy 388.62 -130.63474) (xy 388.62 -130.25374) (xy 388.112 -130.25374)
				)
			)
		)
		(zone
			(layer "B.Cu")
			(hatch none 0.5)
			(connect_pads
				(clearance 0)
			)
			(min_thickness 0.25)
			(keepout
				(tracks allowed)
				(vias not_allowed)
				(pads allowed)
				(copperpour not_allowed)
				(footprints allowed)
			)
			(placement
				(enabled no)
				(sheetname "")
			)
			(fill
				(thermal_gap 0.5)
				(thermal_bridge_width 0.5)
				(island_removal_mode 0)
			)
			(polygon
				(pts
					(xy 388.112 -130.25374) (xy 388.62 -130.25374) (xy 388.62 -130.63474) (xy 388.112 -130.63474)
				)
			)
		)
	)
	(footprint ""
		(layer "B.Cu")
		(at 320.294 -154.813 90)
		(property "Reference" "C4L1"
			(at 0 0 90)
			(layer "B.SilkS")
			(hide yes)
			(effects
				(font
					(size 1.27 1.27)
				)
				(justify mirror)
			)
		)
		(property "Value" ""
			(at 0 0 90)
			(layer "B.Fab")
			(effects
				(font
					(size 1.27 1.27)
				)
				(justify mirror)
			)
		)
		(duplicate_pad_numbers_are_jumpers no)
		(fp_poly
			(pts
				(xy 0.4953 -0.2032) (xy -0.4953 -0.2032) (xy -0.4953 1.6002) (xy 0.4953 1.6002)
			)
			(stroke
				(width 0)
				(type default)
			)
			(fill no)
			(layer "B.CrtYd")
		)
		(fp_line
			(start 0.4953 -0.2032)
			(end -0.4953 -0.2032)
			(stroke
				(width 0.1)
				(type default)
			)
			(layer "B.Fab")
		)
		(fp_line
			(start -0.4953 -0.2032)
			(end -0.4953 1.6002)
			(stroke
				(width 0.1)
				(type default)
			)
			(layer "B.Fab")
		)
		(fp_line
			(start 0.4953 1.6002)
			(end 0.4953 -0.2032)
			(stroke
				(width 0.1)
				(type default)
			)
			(layer "B.Fab")
		)
		(fp_line
			(start -0.4953 1.6002)
			(end 0.4953 1.6002)
			(stroke
				(width 0.1)
				(type default)
			)
			(layer "B.Fab")
		)
		(pad "1" smd rect
			(at 0 0 270)
			(size 0.762 0.889)
			(layers "B.Cu" "B.Mask" "B.Paste")
			(net "PVPP_DEF")
		)
		(pad "2" smd rect
			(at 0 1.397 270)
			(size 0.762 0.889)
			(layers "B.Cu" "B.Mask" "B.Paste")
			(net "GND")
		)
		(zone
			(layer "B.Cu")
			(hatch none 0.5)
			(connect_pads
				(clearance 0)
			)
			(min_thickness 0.25)
			(keepout
				(tracks not_allowed)
				(vias allowed)
				(pads allowed)
				(copperpour not_allowed)
				(footprints allowed)
			)
			(placement
				(enabled no)
				(sheetname "")
			)
			(fill
				(thermal_gap 0.5)
				(thermal_bridge_width 0.5)
				(island_removal_mode 0)
			)
			(polygon
				(pts
					(xy 320.7385 -155.194) (xy 320.7385 -154.432) (xy 321.2465 -154.432) (xy 321.2465 -155.194)
				)
			)
		)
	)
	(footprint ""
		(layer "B.Cu")
		(at 446.912238 -52.407058)
		(property "Reference" "C2R14"
			(at 0 0 0)
			(layer "B.SilkS")
			(hide yes)
			(effects
				(font
					(size 1.27 1.27)
				)
				(justify mirror)
			)
		)
		(property "Value" ""
			(at 0 0 0)
			(layer "B.Fab")
			(effects
				(font
					(size 1.27 1.27)
				)
				(justify mirror)
			)
		)
		(duplicate_pad_numbers_are_jumpers no)
		(fp_poly
			(pts
				(xy -0.3048 -0.1016) (xy -0.3048 0.9906) (xy 0.3048 0.9906) (xy 0.3048 -0.1016)
			)
			(stroke
				(width 0)
				(type default)
			)
			(fill no)
			(layer "B.CrtYd")
		)
		(fp_line
			(start -0.3048 -0.1016)
			(end 0.3048 -0.1016)
			(stroke
				(width 0.1)
				(type default)
			)
			(layer "B.Fab")
		)
		(fp_line
			(start -0.3048 0.9906)
			(end -0.3048 -0.1016)
			(stroke
				(width 0.1)
				(type default)
			)
			(layer "B.Fab")
		)
		(fp_line
			(start 0.3048 -0.1016)
			(end 0.3048 0.9906)
			(stroke
				(width 0.1)
				(type default)
			)
			(layer "B.Fab")
		)
		(fp_line
			(start 0.3048 0.9906)
			(end -0.3048 0.9906)
			(stroke
				(width 0.1)
				(type default)
			)
			(layer "B.Fab")
		)
		(pad "1" smd rect
			(at 0 0 180)
			(size 0.508 0.508)
			(layers "B.Cu" "B.Mask" "B.Paste")
			(net "P3E_CPU0_PE3_OCP_TXP<5>")
		)
		(pad "2" smd rect
			(at 0 0.889 180)
			(size 0.508 0.508)
			(layers "B.Cu" "B.Mask" "B.Paste")
			(net "P3E_OCP_CPU0_PE3_C_TXP<5>")
		)
		(zone
			(layer "B.Cu")
			(hatch none 0.5)
			(connect_pads
				(clearance 0)
			)
			(min_thickness 0.25)
			(keepout
				(tracks allowed)
				(vias not_allowed)
				(pads allowed)
				(copperpour not_allowed)
				(footprints allowed)
			)
			(placement
				(enabled no)
				(sheetname "")
			)
			(fill
				(thermal_gap 0.5)
				(thermal_bridge_width 0.5)
				(island_removal_mode 0)
			)
			(polygon
				(pts
					(xy 447.166238 -52.153058) (xy 446.658238 -52.153058) (xy 446.658238 -51.772058) (xy 447.166238 -51.772058)
				)
			)
		)
		(zone
			(layer "B.Cu")
			(hatch none 0.5)
			(connect_pads
				(clearance 0)
			)
			(min_thickness 0.25)
			(keepout
				(tracks not_allowed)
				(vias allowed)
				(pads allowed)
				(copperpour not_allowed)
				(footprints allowed)
			)
			(placement
				(enabled no)
				(sheetname "")
			)
			(fill
				(thermal_gap 0.5)
				(thermal_bridge_width 0.5)
				(island_removal_mode 0)
			)
			(polygon
				(pts
					(xy 447.166238 -51.772058) (xy 446.658238 -51.772058) (xy 446.658238 -52.153058) (xy 447.166238 -52.153058)
				)
			)
		)
	)
)
